(kicad_pcb
	(version 20260206)
	(generator "pcbnew")
	(generator_version "10.0")
	(general
		(thickness 1.6)
		(legacy_teardrops no)
	)
	(paper "A4")
	(title_block
		(title "Bryce Canyon_F.DPB_16315-1-OCP.brd")
		(comment 1 "Bryce Canyon / footprints 1279-1281 of 2223")
	)
	(layers
		(0 "F.Cu" signal "TOP")
		(4 "In1.Cu" signal "L2GND")
		(6 "In2.Cu" signal "L3")
		(8 "In3.Cu" signal "L4GND")
		(10 "In4.Cu" signal "L5")
		(12 "In5.Cu" signal "L6VCC")
		(14 "In6.Cu" signal "L7VCC")
		(16 "In7.Cu" signal "L8")
		(18 "In8.Cu" signal "L9GND")
		(20 "In9.Cu" signal "L10")
		(22 "In10.Cu" signal "L11GND")
		(2 "B.Cu" signal "BOTTOM")
		(9 "F.Adhes" user "F.Adhesive")
		(11 "B.Adhes" user "B.Adhesive")
		(13 "F.Paste" user "Package Geometry/Pastemask Top")
		(15 "B.Paste" user "Package Geometry/Pastemask Bottom")
		(5 "F.SilkS" user "Ref Des/Silkscreen Top")
		(7 "B.SilkS" user "Ref Des/Silkscreen Bottom")
		(1 "F.Mask" user "Board Geometry/Soldermask Top")
		(3 "B.Mask" user "Board Geometry/Soldermask Bottom")
		(17 "Dwgs.User" user "User.Drawings")
		(19 "Cmts.User" user "User.Comments")
		(21 "Eco1.User" user "User.Eco1")
		(23 "Eco2.User" user "User.Eco2")
		(25 "Edge.Cuts" user "Board Geometry/Outline")
		(27 "Margin" user)
		(31 "F.CrtYd" user "Package Geometry/Place Bound Top")
		(29 "B.CrtYd" user "Package Geometry/Place Bound Bottom")
		(35 "F.Fab" user "Ref Des/Assembly Top")
		(33 "B.Fab" user "Ref Des/Assembly Bottom")
	)
	(footprint ""
		(layer "F.Cu")
		(at 213.300056 -4.500118)
		(property "Reference" "LED1"
			(at 0 0 0)
			(layer "F.SilkS")
			(hide yes)
			(effects
				(font
					(size 1.27 1.27)
				)
			)
		)
		(property "Value" "AMP-CONN40D-GP"
			(at -13.74775 -0.720598 0)
			(unlocked yes)
			(layer "F.Fab")
			(hide yes)
			(effects
				(font
					(size 1.016 1.016)
					(thickness 0.1524)
				)
			)
		)
		(property "Device Type" "G846A40120T1HR"
			(at -13.74775 -2.244598 0)
			(unlocked yes)
			(layer "F.Fab")
			(hide yes)
			(effects
				(font
					(size 1.016 1.016)
					(thickness 0.1524)
				)
			)
		)
		(duplicate_pad_numbers_are_jumpers no)
		(fp_line
			(start -12.5095 0.254)
			(end -11.557 0.254)
			(stroke
				(width 0.1524)
				(type default)
			)
			(layer "F.SilkS")
		)
		(fp_line
			(start -12.5095 2.8194)
			(end -12.5095 0.254)
			(stroke
				(width 0.1524)
				(type default)
			)
			(layer "F.SilkS")
		)
		(fp_line
			(start -11.557 -2.5527)
			(end -10.0584 -2.5527)
			(stroke
				(width 0.1524)
				(type default)
			)
			(layer "F.SilkS")
		)
		(fp_line
			(start -11.557 0.254)
			(end -11.557 -2.5527)
			(stroke
				(width 0.1524)
				(type default)
			)
			(layer "F.SilkS")
		)
		(fp_line
			(start -10.1473 -4.1402)
			(end -10.1473 -3.0607)
			(stroke
				(width 0.3302)
				(type default)
			)
			(layer "F.SilkS")
		)
		(fp_line
			(start -10.0584 -4.0513)
			(end 10.0584 -4.0513)
			(stroke
				(width 0.1524)
				(type default)
			)
			(layer "F.SilkS")
		)
		(fp_line
			(start -10.0584 -2.5527)
			(end -10.0584 -4.0513)
			(stroke
				(width 0.1524)
				(type default)
			)
			(layer "F.SilkS")
		)
		(fp_line
			(start -10.0584 2.8194)
			(end -12.5095 2.8194)
			(stroke
				(width 0.1524)
				(type default)
			)
			(layer "F.SilkS")
		)
		(fp_line
			(start -10.0584 4.0513)
			(end -10.0584 2.8194)
			(stroke
				(width 0.1524)
				(type default)
			)
			(layer "F.SilkS")
		)
		(fp_line
			(start -9.1059 -4.1402)
			(end -10.1473 -4.1402)
			(stroke
				(width 0.3302)
				(type default)
			)
			(layer "F.SilkS")
		)
		(fp_line
			(start 10.0584 -4.0513)
			(end 10.0584 -2.5527)
			(stroke
				(width 0.1524)
				(type default)
			)
			(layer "F.SilkS")
		)
		(fp_line
			(start 10.0584 -2.5527)
			(end 10.795 -2.5527)
			(stroke
				(width 0.1524)
				(type default)
			)
			(layer "F.SilkS")
		)
		(fp_line
			(start 10.0584 2.8194)
			(end 10.0584 4.0513)
			(stroke
				(width 0.1524)
				(type default)
			)
			(layer "F.SilkS")
		)
		(fp_line
			(start 10.0584 4.0513)
			(end -10.0584 4.0513)
			(stroke
				(width 0.1524)
				(type default)
			)
			(layer "F.SilkS")
		)
		(fp_line
			(start 10.795 -2.5527)
			(end 11.557 -1.7907)
			(stroke
				(width 0.1524)
				(type default)
			)
			(layer "F.SilkS")
		)
		(fp_line
			(start 11.557 -1.7907)
			(end 11.557 0.254)
			(stroke
				(width 0.1524)
				(type default)
			)
			(layer "F.SilkS")
		)
		(fp_line
			(start 11.557 0.254)
			(end 12.5095 0.254)
			(stroke
				(width 0.1524)
				(type default)
			)
			(layer "F.SilkS")
		)
		(fp_line
			(start 12.5095 0.254)
			(end 12.5095 2.8194)
			(stroke
				(width 0.1524)
				(type default)
			)
			(layer "F.SilkS")
		)
		(fp_line
			(start 12.5095 2.8194)
			(end 10.0584 2.8194)
			(stroke
				(width 0.1524)
				(type default)
			)
			(layer "F.SilkS")
		)
		(fp_poly
			(pts
				(xy -9.500108 -4.1402) (xy -8.865108 -4.7752) (xy -10.135108 -4.7752)
			)
			(stroke
				(width 0)
				(type default)
			)
			(fill yes)
			(layer "F.SilkS")
		)
		(fp_poly
			(pts
				(xy -9.804908 2.097532) (xy 9.804908 2.097532) (xy 9.804908 -2.097532) (xy -9.804908 -2.097532)
			)
			(stroke
				(width 0)
				(type default)
			)
			(fill yes)
			(layer "F.SilkS")
		)
		(fp_poly
			(pts
				(xy -9.8044 3.302) (xy -9.8044 2.2987) (xy -11.938 2.2987) (xy -11.938 0.508) (xy -11.303 0.508)
				(xy -11.303 -2.2987) (xy -9.8044 -2.2987) (xy -9.8044 -3.302) (xy 9.8044 -3.302) (xy 9.8044 -2.2987)
				(xy 11.303 -2.2987) (xy 11.303 0.508) (xy 11.938 0.508) (xy 11.938 2.2987) (xy 9.8044 2.2987) (xy 9.8044 3.302)
			)
			(stroke
				(width 0)
				(type default)
			)
			(fill no)
			(layer "F.CrtYd")
		)
		(fp_poly
			(pts
				(xy -10.3124 4.3053) (xy -10.3124 3.0734) (xy -12.7635 3.0734) (xy -12.7635 0) (xy -11.811 0) (xy -11.811 -2.8067)
				(xy -10.3124 -2.8067) (xy -10.3124 -4.3053) (xy 10.3124 -4.3053) (xy 10.3124 -2.8067) (xy 11.811 -2.8067)
				(xy 11.811 -0.00635) (xy 11.303 -0.00635) (xy 11.303 -2.2987) (xy 9.8044 -2.2987) (xy 9.8044 -3.302)
				(xy -9.8044 -3.302) (xy -9.8044 -2.2987) (xy -11.303 -2.2987) (xy -11.303 0.508) (xy -11.938 0.508)
				(xy -11.938 2.2987) (xy -9.8044 2.2987) (xy -9.8044 3.302) (xy 9.8044 3.302) (xy 9.8044 2.2987)
				(xy 11.938 2.2987) (xy 11.938 0.508) (xy 11.303 0.508) (xy 11.303 0.00635) (xy 12.7635 0.00635)
				(xy 12.7635 3.0734) (xy 10.3124 3.0734) (xy 10.3124 4.3053)
			)
			(stroke
				(width 0)
				(type default)
			)
			(fill no)
			(layer "F.CrtYd")
		)
		(fp_poly
			(pts
				(xy -10.3124 4.3053) (xy -10.3124 3.0734) (xy -12.7635 3.0734) (xy -12.7635 0) (xy -11.811 0) (xy -11.811 -2.8067)
				(xy -10.3124 -2.8067) (xy -10.3124 -4.3053) (xy 10.3124 -4.3053) (xy 10.3124 -2.8067) (xy 11.811 -2.8067)
				(xy 11.811 0) (xy 12.7635 0) (xy 12.7635 3.0734) (xy 10.3124 3.0734) (xy 10.3124 4.3053)
			)
			(stroke
				(width 0)
				(type default)
			)
			(fill no)
			(layer "F.Fab")
		)
		(pad "1" smd rect
			(at -9.500108 -3.050032)
			(size 0.6096 1.4986)
			(layers "F.Cu" "F.Mask" "F.Paste")
			(net "DRIVE_A_26_FLT_LED")
		)
		(pad "2" smd rect
			(at -9.500108 3.050032)
			(size 0.6096 1.4986)
			(layers "F.Cu" "F.Mask" "F.Paste")
			(net "DRIVE_A_27_FLT_LED")
		)
		(pad "3" smd rect
			(at -8.50011 -3.050032)
			(size 0.6096 1.4986)
			(layers "F.Cu" "F.Mask" "F.Paste")
			(net "DRIVE_A_26_ACT")
		)
		(pad "4" smd rect
			(at -8.50011 3.050032)
			(size 0.6096 1.4986)
			(layers "F.Cu" "F.Mask" "F.Paste")
			(net "DRIVE_A_27_ACT")
		)
		(pad "5" smd rect
			(at -7.500112 -3.050032)
			(size 0.6096 1.4986)
			(layers "F.Cu" "F.Mask" "F.Paste")
			(net "Net_56")
		)
		(pad "6" smd rect
			(at -7.500112 3.050032)
			(size 0.6096 1.4986)
			(layers "F.Cu" "F.Mask" "F.Paste")
			(net "DRIVE_A_28_FLT_LED")
		)
		(pad "7" smd rect
			(at -6.500114 -3.050032)
			(size 0.6096 1.4986)
			(layers "F.Cu" "F.Mask" "F.Paste")
			(net "P5V_A_2")
		)
		(pad "8" smd rect
			(at -6.500114 3.050032)
			(size 0.6096 1.4986)
			(layers "F.Cu" "F.Mask" "F.Paste")
			(net "DRIVE_A_28_ACT")
		)
		(pad "9" smd rect
			(at -5.500116 -3.050032)
			(size 0.6096 1.4986)
			(layers "F.Cu" "F.Mask" "F.Paste")
			(net "P5V_A_2")
		)
		(pad "10" smd rect
			(at -5.500116 3.050032)
			(size 0.6096 1.4986)
			(layers "F.Cu" "F.Mask" "F.Paste")
			(net "DRIVE_A_29_FLT_LED")
		)
		(pad "11" smd rect
			(at -4.500118 -3.050032)
			(size 0.6096 1.4986)
			(layers "F.Cu" "F.Mask" "F.Paste")
			(net "P5V_A_2")
		)
		(pad "12" smd rect
			(at -4.500118 3.050032)
			(size 0.6096 1.4986)
			(layers "F.Cu" "F.Mask" "F.Paste")
			(net "DRIVE_A_29_ACT")
		)
		(pad "13" smd rect
			(at -3.50012 -3.050032)
			(size 0.6096 1.4986)
			(layers "F.Cu" "F.Mask" "F.Paste")
			(net "Net_54")
		)
		(pad "14" smd rect
			(at -3.50012 3.050032)
			(size 0.6096 1.4986)
			(layers "F.Cu" "F.Mask" "F.Paste")
			(net "DRIVE_A_24_FLT_LED")
		)
		(pad "15" smd rect
			(at -2.500122 -3.050032)
			(size 0.6096 1.4986)
			(layers "F.Cu" "F.Mask" "F.Paste")
			(net "GND")
		)
		(pad "16" smd rect
			(at -2.500122 3.050032)
			(size 0.6096 1.4986)
			(layers "F.Cu" "F.Mask" "F.Paste")
			(net "DRIVE_A_24_ACT")
		)
		(pad "17" smd rect
			(at -1.500124 -3.050032)
			(size 0.6096 1.4986)
			(layers "F.Cu" "F.Mask" "F.Paste")
			(net "GND")
		)
		(pad "18" smd rect
			(at -1.500124 3.050032)
			(size 0.6096 1.4986)
			(layers "F.Cu" "F.Mask" "F.Paste")
			(net "DRIVE_A_25_FLT_LED")
		)
		(pad "19" smd rect
			(at -0.500126 -3.050032)
			(size 0.6096 1.4986)
			(layers "F.Cu" "F.Mask" "F.Paste")
			(net "GND")
		)
		(pad "20" smd rect
			(at -0.500126 3.050032)
			(size 0.6096 1.4986)
			(layers "F.Cu" "F.Mask" "F.Paste")
			(net "DRIVE_A_25_ACT")
		)
		(pad "21" smd rect
			(at 0.500126 -3.050032)
			(size 0.6096 1.4986)
			(layers "F.Cu" "F.Mask" "F.Paste")
			(net "DRIVE_A_32_FLT_LED")
		)
		(pad "22" smd rect
			(at 0.500126 3.050032)
			(size 0.6096 1.4986)
			(layers "F.Cu" "F.Mask" "F.Paste")
			(net "DRIVE_A_33_FLT_LED")
		)
		(pad "23" smd rect
			(at 1.500124 -3.050032)
			(size 0.6096 1.4986)
			(layers "F.Cu" "F.Mask" "F.Paste")
			(net "DRIVE_A_32_ACT")
		)
		(pad "24" smd rect
			(at 1.500124 3.050032)
			(size 0.6096 1.4986)
			(layers "F.Cu" "F.Mask" "F.Paste")
			(net "DRIVE_A_33_ACT")
		)
		(pad "25" smd rect
			(at 2.500122 -3.050032)
			(size 0.6096 1.4986)
			(layers "F.Cu" "F.Mask" "F.Paste")
			(net "Net_55")
		)
		(pad "26" smd rect
			(at 2.500122 3.050032)
			(size 0.6096 1.4986)
			(layers "F.Cu" "F.Mask" "F.Paste")
			(net "DRIVE_A_34_FLT_LED")
		)
		(pad "27" smd rect
			(at 3.50012 -3.050032)
			(size 0.6096 1.4986)
			(layers "F.Cu" "F.Mask" "F.Paste")
			(net "P5V_A_2")
		)
		(pad "28" smd rect
			(at 3.50012 3.050032)
			(size 0.6096 1.4986)
			(layers "F.Cu" "F.Mask" "F.Paste")
			(net "DRIVE_A_34_ACT")
		)
		(pad "29" smd rect
			(at 4.500118 -3.050032)
			(size 0.6096 1.4986)
			(layers "F.Cu" "F.Mask" "F.Paste")
			(net "P5V_A_2")
		)
		(pad "30" smd rect
			(at 4.500118 3.050032)
			(size 0.6096 1.4986)
			(layers "F.Cu" "F.Mask" "F.Paste")
			(net "DRIVE_A_35_FLT_LED")
		)
		(pad "31" smd rect
			(at 5.500116 -3.050032)
			(size 0.6096 1.4986)
			(layers "F.Cu" "F.Mask" "F.Paste")
			(net "P5V_A_2")
		)
		(pad "32" smd rect
			(at 5.500116 3.050032)
			(size 0.6096 1.4986)
			(layers "F.Cu" "F.Mask" "F.Paste")
			(net "DRIVE_A_35_ACT")
		)
		(pad "33" smd rect
			(at 6.500114 -3.050032)
			(size 0.6096 1.4986)
			(layers "F.Cu" "F.Mask" "F.Paste")
			(net "Net_53")
		)
		(pad "34" smd rect
			(at 6.500114 3.050032)
			(size 0.6096 1.4986)
			(layers "F.Cu" "F.Mask" "F.Paste")
			(net "DRIVE_A_30_FLT_LED")
		)
		(pad "35" smd rect
			(at 7.500112 -3.050032)
			(size 0.6096 1.4986)
			(layers "F.Cu" "F.Mask" "F.Paste")
			(net "GND")
		)
		(pad "36" smd rect
			(at 7.500112 3.050032)
			(size 0.6096 1.4986)
			(layers "F.Cu" "F.Mask" "F.Paste")
			(net "DRIVE_A_30_ACT")
		)
		(pad "37" smd rect
			(at 8.50011 -3.050032)
			(size 0.6096 1.4986)
			(layers "F.Cu" "F.Mask" "F.Paste")
			(net "GND")
		)
		(pad "38" smd rect
			(at 8.50011 3.050032)
			(size 0.6096 1.4986)
			(layers "F.Cu" "F.Mask" "F.Paste")
			(net "DRIVE_A_31_FLT_LED")
		)
		(pad "39" smd rect
			(at 9.500108 -3.050032)
			(size 0.6096 1.4986)
			(layers "F.Cu" "F.Mask" "F.Paste")
			(net "GND")
		)
		(pad "40" smd rect
			(at 9.500108 3.050032)
			(size 0.6096 1.4986)
			(layers "F.Cu" "F.Mask" "F.Paste")
			(net "DRIVE_A_31_ACT")
		)
		(pad "41" smd rect
			(at 11.500104 1.549908)
			(size 1.4986 2.0066)
			(layers "F.Cu" "F.Mask" "F.Paste")
			(net "GND")
		)
		(pad "42" smd rect
			(at -11.500104 1.549908)
			(size 1.4986 2.0066)
			(layers "F.Cu" "F.Mask" "F.Paste")
			(net "GND")
		)
		(zone
			(layer "F.Cu")
			(hatch none 0.5)
			(connect_pads
				(clearance 0)
			)
			(min_thickness 0.25)
			(keepout
				(tracks allowed)
				(vias not_allowed)
				(pads allowed)
				(copperpour not_allowed)
				(footprints allowed)
			)
			(placement
				(enabled no)
				(sheetname "")
			)
			(fill
				(thermal_gap 0.5)
				(thermal_bridge_width 0.5)
				(island_removal_mode 0)
			)
			(polygon
				(pts
					(xy 203.495148 -6.29285) (xy 223.104964 -6.29285) (xy 223.104964 -6.80085) (xy 203.495148 -6.80085)
				)
			)
		)
		(zone
			(layer "F.Cu")
			(hatch none 0.5)
			(connect_pads
				(clearance 0)
			)
			(min_thickness 0.25)
			(keepout
				(tracks allowed)
				(vias not_allowed)
				(pads allowed)
				(copperpour not_allowed)
				(footprints allowed)
			)
			(placement
				(enabled no)
				(sheetname "")
			)
			(fill
				(thermal_gap 0.5)
				(thermal_bridge_width 0.5)
				(island_removal_mode 0)
			)
			(polygon
				(pts
					(xy 203.495148 -2.199386) (xy 223.104964 -2.199386) (xy 223.104964 -6.80085) (xy 203.495148 -6.80085)
				)
			)
		)
		(zone
			(layer "F.Cu")
			(hatch none 0.5)
			(connect_pads
				(clearance 0)
			)
			(min_thickness 0.25)
			(keepout
				(tracks not_allowed)
				(vias allowed)
				(pads allowed)
				(copperpour not_allowed)
				(footprints allowed)
			)
			(placement
				(enabled no)
				(sheetname "")
			)
			(fill
				(thermal_gap 0.5)
				(thermal_bridge_width 0.5)
				(island_removal_mode 0)
			)
			(polygon
				(pts
					(xy 203.495148 -2.199386) (xy 223.104964 -2.199386) (xy 223.104964 -6.80085) (xy 203.495148 -6.80085)
				)
			)
		)
		(zone
			(layer "F.Cu")
			(hatch none 0.5)
			(connect_pads
				(clearance 0)
			)
			(min_thickness 0.25)
			(keepout
				(tracks allowed)
				(vias not_allowed)
				(pads allowed)
				(copperpour not_allowed)
				(footprints allowed)
			)
			(placement
				(enabled no)
				(sheetname "")
			)
			(fill
				(thermal_gap 0.5)
				(thermal_bridge_width 0.5)
				(island_removal_mode 0)
			)
			(polygon
				(pts
					(xy 203.495148 -2.199386) (xy 223.104964 -2.199386) (xy 223.104964 -2.707386) (xy 203.495148 -2.707386)
				)
			)
		)
	)
	(footprint ""
		(layer "F.Cu")
		(at 87.036148 -301.287942)
		(property "Reference" "C72"
			(at 0 0 0)
			(layer "F.SilkS")
			(hide yes)
			(effects
				(font
					(size 1.27 1.27)
				)
			)
		)
		(property "Value" "SC4D7U25V5KX-1-GP"
			(at -0.0762 -6.1214 0)
			(unlocked yes)
			(layer "F.Fab")
			(hide yes)
			(effects
				(font
					(size 1.016 1.016)
					(thickness 0.1524)
				)
			)
		)
		(property "Device Type" "C805H58"
			(at -0.0762 -8.1534 0)
			(unlocked yes)
			(layer "F.Fab")
			(hide yes)
			(effects
				(font
					(size 1.016 1.016)
					(thickness 0.1524)
				)
			)
		)
		(duplicate_pad_numbers_are_jumpers no)
		(fp_line
			(start 0.635 0)
			(end -0.635 0)
			(stroke
				(width 0.508)
				(type default)
			)
			(layer "F.SilkS")
		)
		(fp_rect
			(start -0.9652 1.778)
			(end 0.9652 -1.778)
			(stroke
				(width 0)
				(type default)
			)
			(fill no)
			(layer "F.CrtYd")
		)
		(fp_poly
			(pts
				(xy -0.9652 -1.778) (xy 0.9652 -1.778) (xy 0.9652 1.778) (xy -0.9652 1.778)
			)
			(stroke
				(width 0)
				(type default)
			)
			(fill no)
			(layer "F.Fab")
		)
		(pad "1" smd rect
			(at 0 -0.9652)
			(size 1.397 1.143)
			(layers "F.Cu" "F.Mask" "F.Paste")
			(net "P12V_HDD2")
		)
		(pad "2" smd rect
			(at 0 0.9652)
			(size 1.397 1.143)
			(layers "F.Cu" "F.Mask" "F.Paste")
			(net "GND")
		)
	)
	(footprint ""
		(layer "F.Cu")
		(at 365.052102 -188.954918 180)
		(property "Reference" "C292"
			(at 0 0 180)
			(layer "F.SilkS")
			(hide yes)
			(effects
				(font
					(size 1.27 1.27)
				)
			)
		)
		(property "Value" "SC4D7U25V5KX-1-GP"
			(at -0.0762 -6.1214 180)
			(unlocked yes)
			(layer "F.Fab")
			(hide yes)
			(effects
				(font
					(size 1.016 1.016)
					(thickness 0.1524)
				)
			)
		)
		(property "Device Type" "C805H58"
			(at -0.0762 -8.1534 180)
			(unlocked yes)
			(layer "F.Fab")
			(hide yes)
			(effects
				(font
					(size 1.016 1.016)
					(thickness 0.1524)
				)
			)
		)
		(duplicate_pad_numbers_are_jumpers no)
		(fp_line
			(start 0.635 0)
			(end -0.635 0)
			(stroke
				(width 0.508)
				(type default)
			)
			(layer "F.SilkS")
		)
		(fp_rect
			(start -0.9652 1.778)
			(end 0.9652 -1.778)
			(stroke
				(width 0)
				(type default)
			)
			(fill no)
			(layer "F.CrtYd")
		)
		(fp_poly
			(pts
				(xy -0.9652 -1.778) (xy 0.9652 -1.778) (xy 0.9652 1.778) (xy -0.9652 1.778)
			)
			(stroke
				(width 0)
				(type default)
			)
			(fill no)
			(layer "F.Fab")
		)
		(pad "1" smd rect
			(at 0 -0.9652 180)
			(size 1.397 1.143)
			(layers "F.Cu" "F.Mask" "F.Paste")
			(net "P12V_HDD19")
		)
		(pad "2" smd rect
			(at 0 0.9652 180)
			(size 1.397 1.143)
			(layers "F.Cu" "F.Mask" "F.Paste")
			(net "GND")
		)
	)
)
